# Stackup_F0T_PDB_Converter_10L_2p36mm_IT-170GT_RTF_Rev0p2_20211201.xls — Information (pcb-stackup)
| Stackup Information : |  |  |  |
| Stackup Type |  |  | Single Material |
| Project Name |  |  | F0T |
| Board Class |  |  | PDB_Converter |
| Number of Layers |  |  | 10 |
| PCB Material |  |  | IT-170GT |
| Copper Foil |  |  | RTF (Roughness < 4um) |
| PCB Thickness (mm) |  |  | 2.36 |
| PCB Thickness (mil) |  |  | 92.9 |
| Aspect Ratio |  |  | 9.48 |
| Last Update |  |  | 44531 |
| Revision |  |  | 0.2 |
| Creator |  |  | Allen |
| Loss Requirement Table : |  |  |  |
| SDD21 @ Freq(GHz) |  |  |  |
| Requirement (db/inch) | Layer |  |  |
|  | Loss |  |  |
| Stackup History : |  |  |  |
| Date (yyyy/mm/dd) | Revision | Notes |  |
| 44490 | 0.1 | First release |  |
| 44531 | 0.2 | Update material from EM-370(Z) to IT-170(GT) |  |
